# BASEBOARD_FAB2 (Tioga Pass) — schematic netlist excerpt (pin names and nets, part order shuffled) for the footprints in the layout excerpt that follows; sources: Cadence DE-HDL packaged netlist, KiCad conversion of Wiwynn_Tioga_Pass_MB.brd

C7A13  SC22U16V5MX-4-GP  20%  pkg SMD-BCG5  page 236 : \1\ = VR_FET_SW_P12V_STBY_PVDDQ_DEF ; \2\ = GND
C4E20  CAP_A  0.1UF 16V 10% X7R  pkg 0402V  page 202 : A = VR_FET_SW_P12V_STBY_PVCCIN_CPU0 ; B = GND
R9E18  RES  0.0 5% CHIP  pkg 0402  page 139 : A = XTAL_25MHZ_OUT_R ; B = XTAL_25MHZ_OUT

(kicad_pcb
	(version 20260206)
	(generator "pcbnew")
	(generator_version "10.0")
	(general
		(thickness 1.6)
		(legacy_teardrops no)
	)
	(paper "A4")
	(title_block
		(title "Wiwynn_Tioga_Pass_MB.brd")
		(comment 1 "Tioga Pass / footprints 933-935 of 4770")
	)
	(layers
		(0 "F.Cu" signal "TOP")
		(4 "In1.Cu" signal "L2GND")
		(6 "In2.Cu" signal "L3")
		(8 "In3.Cu" signal "L4GND")
		(10 "In4.Cu" signal "L5")
		(12 "In5.Cu" signal "L6GND")
		(14 "In6.Cu" signal "L7VCC")
		(16 "In7.Cu" signal "L8VCC")
		(18 "In8.Cu" signal "L9GND")
		(20 "In9.Cu" signal "L10")
		(22 "In10.Cu" signal "L11GND")
		(24 "In11.Cu" signal "L12")
		(26 "In12.Cu" signal "L13GND")
		(2 "B.Cu" signal "BOTTOM")
		(9 "F.Adhes" user "F.Adhesive")
		(11 "B.Adhes" user "B.Adhesive")
		(13 "F.Paste" user "Package Geometry/Pastemask Top")
		(15 "B.Paste" user "Package Geometry/Pastemask Bottom")
		(5 "F.SilkS" user "Ref Des/Silkscreen Top")
		(7 "B.SilkS" user "Ref Des/Silkscreen Bottom")
		(1 "F.Mask" user "Board Geometry/Soldermask Top")
		(3 "B.Mask" user "Board Geometry/Soldermask Bottom")
		(17 "Dwgs.User" user "User.Drawings")
		(19 "Cmts.User" user "User.Comments")
		(21 "Eco1.User" user "User.Eco1")
		(23 "Eco2.User" user "User.Eco2")
		(25 "Edge.Cuts" user "Board Geometry/Outline")
		(27 "Margin" user)
		(31 "F.CrtYd" user "Package Geometry/Place Bound Top")
		(29 "B.CrtYd" user "Package Geometry/Place Bound Bottom")
		(35 "F.Fab" user "Ref Des/Assembly Top")
		(33 "B.Fab" user "Ref Des/Assembly Bottom")
	)
	(footprint ""
		(layer "F.Cu")
		(at 477.3041 -42.1894 90)
		(property "Reference" "R9E18"
			(at 0 0 90)
			(layer "F.SilkS")
			(hide yes)
			(effects
				(font
					(size 1.27 1.27)
				)
			)
		)
		(property "Value" ""
			(at 0 0 90)
			(layer "F.Fab")
			(effects
				(font
					(size 1.27 1.27)
				)
			)
		)
		(duplicate_pad_numbers_are_jumpers no)
		(fp_poly
			(pts
				(xy -0.2794 -0.1016) (xy 0.2794 -0.1016) (xy 0.2794 0.9906) (xy -0.2794 0.9906)
			)
			(stroke
				(width 0)
				(type default)
			)
			(fill no)
			(layer "F.CrtYd")
		)
		(fp_line
			(start 0.2794 -0.1016)
			(end -0.2794 -0.1016)
			(stroke
				(width 0.1)
				(type default)
			)
			(layer "F.Fab")
		)
		(fp_line
			(start -0.2794 -0.1016)
			(end -0.2794 0.9906)
			(stroke
				(width 0.1)
				(type default)
			)
			(layer "F.Fab")
		)
		(fp_line
			(start 0.2794 0.9906)
			(end 0.2794 -0.1016)
			(stroke
				(width 0.1)
				(type default)
			)
			(layer "F.Fab")
		)
		(fp_line
			(start -0.2794 0.9906)
			(end 0.2794 0.9906)
			(stroke
				(width 0.1)
				(type default)
			)
			(layer "F.Fab")
		)
		(pad "1" smd rect
			(at 0 0 90)
			(size 0.508 0.508)
			(layers "F.Cu" "F.Mask" "F.Paste")
			(net "XTAL_25MHZ_OUT_R")
		)
		(pad "2" smd rect
			(at 0 0.889 90)
			(size 0.508 0.508)
			(layers "F.Cu" "F.Mask" "F.Paste")
			(net "XTAL_25MHZ_OUT")
		)
		(zone
			(layer "F.Cu")
			(hatch none 0.5)
			(connect_pads
				(clearance 0)
			)
			(min_thickness 0.25)
			(keepout
				(tracks allowed)
				(vias not_allowed)
				(pads allowed)
				(copperpour not_allowed)
				(footprints allowed)
			)
			(placement
				(enabled no)
				(sheetname "")
			)
			(fill
				(thermal_gap 0.5)
				(thermal_bridge_width 0.5)
				(island_removal_mode 0)
			)
			(polygon
				(pts
					(xy 477.5581 -41.9354) (xy 477.5581 -42.4434) (xy 477.9391 -42.4434) (xy 477.9391 -41.9354)
				)
			)
		)
		(zone
			(layer "F.Cu")
			(hatch none 0.5)
			(connect_pads
				(clearance 0)
			)
			(min_thickness 0.25)
			(keepout
				(tracks not_allowed)
				(vias allowed)
				(pads allowed)
				(copperpour not_allowed)
				(footprints allowed)
			)
			(placement
				(enabled no)
				(sheetname "")
			)
			(fill
				(thermal_gap 0.5)
				(thermal_bridge_width 0.5)
				(island_removal_mode 0)
			)
			(polygon
				(pts
					(xy 477.9391 -41.9354) (xy 477.9391 -42.4434) (xy 477.5581 -42.4434) (xy 477.5581 -41.9354)
				)
			)
		)
	)
	(footprint ""
		(layer "F.Cu")
		(at 198.337932 -60.305442 90)
		(property "Reference" "C4E20"
			(at 0 0 90)
			(layer "F.SilkS")
			(hide yes)
			(effects
				(font
					(size 1.27 1.27)
				)
			)
		)
		(property "Value" ""
			(at 0 0 90)
			(layer "F.Fab")
			(effects
				(font
					(size 1.27 1.27)
				)
			)
		)
		(duplicate_pad_numbers_are_jumpers no)
		(fp_rect
			(start 0.3048 0.9906)
			(end -0.3048 -0.1016)
			(stroke
				(width 0)
				(type default)
			)
			(fill no)
			(layer "F.CrtYd")
		)
		(fp_line
			(start 0.3048 -0.1016)
			(end -0.3048 -0.1016)
			(stroke
				(width 0.1)
				(type default)
			)
			(layer "F.Fab")
		)
		(fp_line
			(start -0.3048 -0.1016)
			(end -0.3048 0.9906)
			(stroke
				(width 0.1)
				(type default)
			)
			(layer "F.Fab")
		)
		(fp_line
			(start 0.3048 0.9906)
			(end 0.3048 -0.1016)
			(stroke
				(width 0.1)
				(type default)
			)
			(layer "F.Fab")
		)
		(fp_line
			(start -0.3048 0.9906)
			(end 0.3048 0.9906)
			(stroke
				(width 0.1)
				(type default)
			)
			(layer "F.Fab")
		)
		(pad "1" smd rect
			(at 0 0 90)
			(size 0.508 0.508)
			(layers "F.Cu" "F.Mask" "F.Paste")
			(net "VR_FET_SW_P12V_STBY_PVCCIN_CPU0")
		)
		(pad "2" smd rect
			(at 0 0.889 90)
			(size 0.508 0.508)
			(layers "F.Cu" "F.Mask" "F.Paste")
			(net "GND")
		)
		(zone
			(layer "F.Cu")
			(hatch none 0.5)
			(connect_pads
				(clearance 0)
			)
			(min_thickness 0.25)
			(keepout
				(tracks not_allowed)
				(vias allowed)
				(pads allowed)
				(copperpour not_allowed)
				(footprints allowed)
			)
			(placement
				(enabled no)
				(sheetname "")
			)
			(fill
				(thermal_gap 0.5)
				(thermal_bridge_width 0.5)
				(island_removal_mode 0)
			)
			(polygon
				(pts
					(xy 198.972932 -60.559442) (xy 198.591932 -60.559442) (xy 198.591932 -60.051442) (xy 198.972932 -60.051442)
				)
			)
		)
		(zone
			(layer "F.Cu")
			(hatch none 0.5)
			(connect_pads
				(clearance 0)
			)
			(min_thickness 0.25)
			(keepout
				(tracks allowed)
				(vias not_allowed)
				(pads allowed)
				(copperpour not_allowed)
				(footprints allowed)
			)
			(placement
				(enabled no)
				(sheetname "")
			)
			(fill
				(thermal_gap 0.5)
				(thermal_bridge_width 0.5)
				(island_removal_mode 0)
			)
			(polygon
				(pts
					(xy 198.972932 -60.559442) (xy 198.591932 -60.559442) (xy 198.591932 -60.051442) (xy 198.972932 -60.051442)
				)
			)
		)
	)
	(footprint ""
		(layer "F.Cu")
		(at 365.890556 -156.250894 180)
		(property "Reference" "C7A13"
			(at 0 0 180)
			(layer "F.SilkS")
			(hide yes)
			(effects
				(font
					(size 1.27 1.27)
				)
			)
		)
		(property "Value" "*"
			(at -0.0762 -6.2357 180)
			(unlocked yes)
			(layer "F.Fab")
			(hide yes)
			(effects
				(font
					(size 1.27 1.016)
					(thickness 0.1524)
				)
			)
		)
		(property "Device Type" "SC22U16V5MX-4-GP_SMD-BCG5-SC22A"
			(at -0.0762 -8.2677 180)
			(unlocked yes)
			(layer "F.Fab")
			(hide yes)
			(effects
				(font
					(size 1.27 1.016)
					(thickness 0.1524)
				)
			)
		)
		(duplicate_pad_numbers_are_jumpers no)
		(fp_line
			(start 0.635 0)
			(end -0.635 0)
			(stroke
				(width 0.508)
				(type default)
			)
			(layer "F.SilkS")
		)
		(fp_rect
			(start -0.9652 1.778)
			(end 0.9652 -1.778)
			(stroke
				(width 0)
				(type default)
			)
			(fill no)
			(layer "F.CrtYd")
		)
		(fp_poly
			(pts
				(xy -0.9652 -1.778) (xy 0.9652 -1.778) (xy 0.9652 1.778) (xy -0.9652 1.778)
			)
			(stroke
				(width 0)
				(type default)
			)
			(fill no)
			(layer "F.Fab")
		)
		(pad "1" smd rect
			(at 0 -0.9652 180)
			(size 1.397 1.143)
			(layers "F.Cu" "F.Mask" "F.Paste")
			(net "VR_FET_SW_P12V_STBY_PVDDQ_DEF")
		)
		(pad "2" smd rect
			(at 0 0.9652 180)
			(size 1.397 1.143)
			(layers "F.Cu" "F.Mask" "F.Paste")
			(net "GND")
		)
	)
)
